# BASEBOARD_FAB2 (Tioga Pass) — schematic netlist excerpt (pin names and nets, part order shuffled) for the footprints in the layout excerpt that follows; sources: Cadence DE-HDL packaged netlist, KiCad conversion of Wiwynn_Tioga_Pass_MB.brd

EU3P1  PXE1110B  IC  pkg QFN  page 211
  DNC(0)  = NC
  DNC(1)  = NC
  BPWM1  = NC
  DNC(2)  = NC
  APWM1  = VR_PVCCIO_CPU0_PWM1
  SDA  = SMB_VR_STBY_LVC3_SDA
  SCL  = SMB_VR_STBY_LVC3_SCL
  RESET_N  = NC
  AVRRDY  = PWRGD_PVCCIO_CPU0_R
  AVREN  = VR_PVCCIO_CPU0_EN
  VRHOT_N  = IRQ_PVCCIO_CPU0_VRHOT_N
  PINALRT_N  = NC
  MP0  = NC
  MP1  = NC
  VCLK  = SVID_CLK_PVCCIO_CPU0
  VDIO  = SVID_VDIO_PVCCIO_CPU0
  VALRT_N  = SVID_ALERT_PVCCIO_CPU0
  MP2  = NC
  AVSEN  = VR_PVCCIO_CPU0_AVSP
  AVREF  = VSENSE_PVCCIO_CPU0_AVSN
  AIREF1  = VR_PVCCIO_CPU0_AIREF1
  AISEN1  = ISENSE_PVCCIO_CPU0_PH1_IMON
  GND(1)  = GND
  DNC(3)  = NC
  BIREF1  = NC
  BISEN1  = GND
  GND(0)  = GND
  DNC(4)  = NC
  BVSEN  = NC
  BVREF  = NC
  MP3  = NC
  MP4  = PU_VR_PVCCIO_CPU0_FAULT1
  XADDR2  = VR_PVCCIO_CPU0_XADDR2
  BTSEN  = NC
  ATSEN  = A_TSENSE_PVCCIO_CPU0
  XADDR1  = VR_PVCCIO_CPU0_XADDR1
  VINSEN  = VR_PVCCIO_CPU0_VINSEN
  IINSEN  = NC
  VDD  = VR_PVCCIO_CPU0_VDD
  VD12  = VR_PVCCIO_CPU0_VD12
  THPAD  = GND

(kicad_pcb
	(version 20260206)
	(generator "pcbnew")
	(generator_version "10.0")
	(general
		(thickness 1.6)
		(legacy_teardrops no)
	)
	(paper "A4")
	(title_block
		(title "Wiwynn_Tioga_Pass_MB.brd")
		(comment 1 "Tioga Pass / footprint 3922 of 4770 (EU3P1), pads 35-41 of 41")
	)
	(layers
		(0 "F.Cu" signal "TOP")
		(4 "In1.Cu" signal "L2GND")
		(6 "In2.Cu" signal "L3")
		(8 "In3.Cu" signal "L4GND")
		(10 "In4.Cu" signal "L5")
		(12 "In5.Cu" signal "L6GND")
		(14 "In6.Cu" signal "L7VCC")
		(16 "In7.Cu" signal "L8VCC")
		(18 "In8.Cu" signal "L9GND")
		(20 "In9.Cu" signal "L10")
		(22 "In10.Cu" signal "L11GND")
		(24 "In11.Cu" signal "L12")
		(26 "In12.Cu" signal "L13GND")
		(2 "B.Cu" signal "BOTTOM")
		(9 "F.Adhes" user "F.Adhesive")
		(11 "B.Adhes" user "B.Adhesive")
		(13 "F.Paste" user "Package Geometry/Pastemask Top")
		(15 "B.Paste" user "Package Geometry/Pastemask Bottom")
		(5 "F.SilkS" user "Ref Des/Silkscreen Top")
		(7 "B.SilkS" user "Ref Des/Silkscreen Bottom")
		(1 "F.Mask" user "Board Geometry/Soldermask Top")
		(3 "B.Mask" user "Board Geometry/Soldermask Bottom")
		(17 "Dwgs.User" user "User.Drawings")
		(19 "Cmts.User" user "User.Comments")
		(21 "Eco1.User" user "User.Eco1")
		(23 "Eco2.User" user "User.Eco2")
		(25 "Edge.Cuts" user "Board Geometry/Outline")
		(27 "Margin" user)
		(31 "F.CrtYd" user "Package Geometry/Place Bound Top")
		(29 "B.CrtYd" user "Package Geometry/Place Bound Bottom")
		(35 "F.Fab" user "Ref Des/Assembly Top")
		(33 "B.Fab" user "Ref Des/Assembly Bottom")
	)
	(footprint ""
		(layer "B.Cu")
		(at 346.5322 -87.4522 -90)
		(property "Reference" "EU3P1"
			(at -1.80975 3.2893 0)
			(unlocked yes)
			(layer "B.SilkS")
			(effects
				(font
					(size 0.7874 0.5842)
					(thickness 0.1524)
				)
				(justify left mirror)
			)
		)
		(property "Value" ""
			(at 0 0 90)
			(layer "B.Fab")
			(effects
				(font
					(size 1.27 1.27)
				)
				(justify mirror)
			)
		)
		(duplicate_pad_numbers_are_jumpers no)
		(pad "35" smd custom
			(at -0.199898 -2.4511 90)
			(size 0.0508 0.0508)
			(layers "B.Cu" "B.Mask" "B.Paste")
			(net "A_TSENSE_PVCCIO_CPU0")
			(options
				(clearance outline)
				(anchor circle)
			)
			(primitives
				(gr_poly
					(pts
						(arc
							(start 0.1016 -0.254)
							(mid 0 -0.3556)
							(end -0.1016 -0.254)
						)
						(xy -0.1016 0.3556) (xy 0.1016 0.3556)
					)
					(width 0)
					(fill yes)
				)
			)
		)
		(pad "36" smd custom
			(at 0.199898 -2.4511 90)
			(size 0.0508 0.0508)
			(layers "B.Cu" "B.Mask" "B.Paste")
			(net "VR_PVCCIO_CPU0_XADDR1")
			(options
				(clearance outline)
				(anchor circle)
			)
			(primitives
				(gr_poly
					(pts
						(arc
							(start 0.1016 -0.254)
							(mid 0 -0.3556)
							(end -0.1016 -0.254)
						)
						(xy -0.1016 0.3556) (xy 0.1016 0.3556)
					)
					(width 0)
					(fill yes)
				)
			)
		)
		(pad "37" smd custom
			(at 0.599948 -2.4511 90)
			(size 0.0508 0.0508)
			(layers "B.Cu" "B.Mask" "B.Paste")
			(net "VR_PVCCIO_CPU0_VINSEN")
			(options
				(clearance outline)
				(anchor circle)
			)
			(primitives
				(gr_poly
					(pts
						(arc
							(start 0.1016 -0.254)
							(mid 0 -0.3556)
							(end -0.1016 -0.254)
						)
						(xy -0.1016 0.3556) (xy 0.1016 0.3556)
					)
					(width 0)
					(fill yes)
				)
			)
		)
		(pad "38" smd custom
			(at 0.999998 -2.4511 90)
			(size 0.0508 0.0508)
			(layers "B.Cu" "B.Mask" "B.Paste")
			(net "Net_265")
			(options
				(clearance outline)
				(anchor circle)
			)
			(primitives
				(gr_poly
					(pts
						(arc
							(start 0.1016 -0.254)
							(mid 0 -0.3556)
							(end -0.1016 -0.254)
						)
						(xy -0.1016 0.3556) (xy 0.1016 0.3556)
					)
					(width 0)
					(fill yes)
				)
			)
		)
		(pad "39" smd custom
			(at 1.400048 -2.4511 90)
			(size 0.0508 0.0508)
			(layers "B.Cu" "B.Mask" "B.Paste")
			(net "VR_PVCCIO_CPU0_VDD")
			(options
				(clearance outline)
				(anchor circle)
			)
			(primitives
				(gr_poly
					(pts
						(arc
							(start 0.1016 -0.254)
							(mid 0 -0.3556)
							(end -0.1016 -0.254)
						)
						(xy -0.1016 0.3556) (xy 0.1016 0.3556)
					)
					(width 0)
					(fill yes)
				)
			)
		)
		(pad "40" smd custom
			(at 1.800098 -2.4511 90)
			(size 0.0508 0.0508)
			(layers "B.Cu" "B.Mask" "B.Paste")
			(net "VR_PVCCIO_CPU0_VD12")
			(options
				(clearance outline)
				(anchor circle)
			)
			(primitives
				(gr_poly
					(pts
						(arc
							(start 0.1016 -0.254)
							(mid 0 -0.3556)
							(end -0.1016 -0.254)
						)
						(xy -0.1016 0.3556) (xy 0.1016 0.3556)
					)
					(width 0)
					(fill yes)
				)
			)
		)
		(pad "41" smd rect
			(at 0 0 90)
			(size 3.683 3.683)
			(layers "B.Cu" "B.Mask" "B.Paste")
			(net "GND")
		)
	)
)
